# S9S_MB_2U (Grand Teton) — schematic netlist excerpt (pin names and nets, part order shuffled) for the footprints in the layout excerpt that follows; sources: Cadence DE-HDL packaged netlist, KiCad conversion of 03242023_DA0F0TMBIJ0_F0T_Motherboard_J_brd_V01_OCP.brd

R4572  Q_RES  0 5% EMPTY  pkg 0402LF  page 146 : A = GPU_3V3IO_RSVD1_FFU ; B = GPU_3V3IO_RSVD1_FFU_ISO
R4651  Q_RES  0 5% CHIP  pkg 0402LF  page 167 : A = FM_P2E_EN2_N ; B = CLK_GEN2_GPU_FPGA_OE_OR_N

(kicad_pcb
	(version 20260206)
	(generator "pcbnew")
	(generator_version "10.0")
	(general
		(thickness 1.6)
		(legacy_teardrops no)
	)
	(paper "A4")
	(title_block
		(title "03242023_DA0F0TMBIJ0_F0T_Motherboard_J_brd_V01_OCP.brd")
		(comment 1 "Grand Teton / footprints 3507-3508 of 6105")
	)
	(layers
		(0 "F.Cu" signal "TOP")
		(4 "In1.Cu" signal "GND")
		(6 "In2.Cu" signal "IN1")
		(8 "In3.Cu" signal "GND1")
		(10 "In4.Cu" signal "IN2")
		(12 "In5.Cu" signal "GND2")
		(14 "In6.Cu" signal "IN3")
		(16 "In7.Cu" signal "GND3")
		(18 "In8.Cu" signal "VCC")
		(20 "In9.Cu" signal "VCC1")
		(22 "In10.Cu" signal "GND4")
		(24 "In11.Cu" signal "IN4")
		(26 "In12.Cu" signal "GND5")
		(28 "In13.Cu" signal "IN5")
		(30 "In14.Cu" signal "GND6")
		(32 "In15.Cu" signal "IN6")
		(34 "In16.Cu" signal "GND7")
		(2 "B.Cu" signal "BOTTOM")
		(9 "F.Adhes" user "F.Adhesive")
		(11 "B.Adhes" user "B.Adhesive")
		(13 "F.Paste" user "Package Geometry/Pastemask Top")
		(15 "B.Paste" user "Package Geometry/Pastemask Bottom")
		(5 "F.SilkS" user "Ref Des/Silkscreen Top")
		(7 "B.SilkS" user "Ref Des/Silkscreen Bottom")
		(1 "F.Mask" user "Board Geometry/Soldermask Top")
		(3 "B.Mask" user "Board Geometry/Soldermask Bottom")
		(17 "Dwgs.User" user "User.Drawings")
		(19 "Cmts.User" user "User.Comments")
		(21 "Eco1.User" user "User.Eco1")
		(23 "Eco2.User" user "User.Eco2")
		(25 "Edge.Cuts" user "Board Geometry/Outline")
		(27 "Margin" user)
		(31 "F.CrtYd" user "Package Geometry/Place Bound Top")
		(29 "B.CrtYd" user "Package Geometry/Place Bound Bottom")
		(35 "F.Fab" user "Ref Des/Assembly Top")
		(33 "B.Fab" user "Ref Des/Assembly Bottom")
	)
	(footprint ""
		(layer "F.Cu")
		(at 46.085506 -395.699996)
		(property "Reference" "R4651"
			(at 0 0 0)
			(layer "F.SilkS")
			(hide yes)
			(effects
				(font
					(size 1.27 1.27)
				)
			)
		)
		(property "Value" ""
			(at 0 0 0)
			(layer "F.Fab")
			(effects
				(font
					(size 1.27 1.27)
				)
			)
		)
		(duplicate_pad_numbers_are_jumpers no)
		(fp_line
			(start -0.7874 -0.4064)
			(end 0.7874 -0.4064)
			(stroke
				(width 0.1524)
				(type default)
			)
			(layer "F.SilkS")
		)
		(fp_line
			(start -0.7874 0.4064)
			(end -0.7874 -0.4064)
			(stroke
				(width 0.1524)
				(type default)
			)
			(layer "F.SilkS")
		)
		(fp_line
			(start 0.7874 -0.4064)
			(end 0.7874 0.4064)
			(stroke
				(width 0.1524)
				(type default)
			)
			(layer "F.SilkS")
		)
		(fp_line
			(start 0.7874 0.4064)
			(end -0.7874 0.4064)
			(stroke
				(width 0.1524)
				(type default)
			)
			(layer "F.SilkS")
		)
		(fp_line
			(start -0.67945 -0.305054)
			(end -0.12065 -0.305054)
			(stroke
				(width 0.1)
				(type default)
			)
			(layer "F.Fab")
		)
		(fp_line
			(start -0.67945 0.3048)
			(end -0.67945 -0.305054)
			(stroke
				(width 0.1)
				(type default)
			)
			(layer "F.Fab")
		)
		(fp_line
			(start -0.12065 -0.305054)
			(end -0.12065 -0.2794)
			(stroke
				(width 0.1)
				(type default)
			)
			(layer "F.Fab")
		)
		(fp_line
			(start -0.12065 -0.2794)
			(end 0.12065 -0.2794)
			(stroke
				(width 0.1)
				(type default)
			)
			(layer "F.Fab")
		)
		(fp_line
			(start -0.12065 0.2794)
			(end -0.12065 0.3048)
			(stroke
				(width 0.1)
				(type default)
			)
			(layer "F.Fab")
		)
		(fp_line
			(start -0.12065 0.3048)
			(end -0.67945 0.3048)
			(stroke
				(width 0.1)
				(type default)
			)
			(layer "F.Fab")
		)
		(fp_line
			(start 0.120396 0.2794)
			(end -0.12065 0.2794)
			(stroke
				(width 0.1)
				(type default)
			)
			(layer "F.Fab")
		)
		(fp_line
			(start 0.120396 0.3048)
			(end 0.120396 0.2794)
			(stroke
				(width 0.1)
				(type default)
			)
			(layer "F.Fab")
		)
		(fp_line
			(start 0.12065 -0.3048)
			(end 0.67945 -0.3048)
			(stroke
				(width 0.1)
				(type default)
			)
			(layer "F.Fab")
		)
		(fp_line
			(start 0.12065 -0.2794)
			(end 0.12065 -0.3048)
			(stroke
				(width 0.1)
				(type default)
			)
			(layer "F.Fab")
		)
		(fp_line
			(start 0.67945 -0.3048)
			(end 0.67945 0.3048)
			(stroke
				(width 0.1)
				(type default)
			)
			(layer "F.Fab")
		)
		(fp_line
			(start 0.67945 0.3048)
			(end 0.120396 0.3048)
			(stroke
				(width 0.1)
				(type default)
			)
			(layer "F.Fab")
		)
		(pad "1" smd circle
			(at -0.40005 0)
			(size 0 0)
			(layers "F.Cu" "F.Mask" "F.Paste")
			(net "FM_P2E_EN2_N")
		)
		(pad "2" smd circle
			(at 0.40005 0)
			(size 0 0)
			(layers "F.Cu" "F.Mask" "F.Paste")
			(net "CLK_GEN2_GPU_FPGA_OE_OR_N")
		)
	)
	(footprint ""
		(layer "F.Cu")
		(at 308.96687 -428.9298)
		(property "Reference" "R4572"
			(at 0 0 0)
			(layer "F.SilkS")
			(hide yes)
			(effects
				(font
					(size 1.27 1.27)
				)
			)
		)
		(property "Value" ""
			(at 0 0 0)
			(layer "F.Fab")
			(effects
				(font
					(size 1.27 1.27)
				)
			)
		)
		(duplicate_pad_numbers_are_jumpers no)
		(fp_line
			(start -0.7874 -0.4064)
			(end 0.7874 -0.4064)
			(stroke
				(width 0.1524)
				(type default)
			)
			(layer "F.SilkS")
		)
		(fp_line
			(start -0.7874 0.4064)
			(end -0.7874 -0.4064)
			(stroke
				(width 0.1524)
				(type default)
			)
			(layer "F.SilkS")
		)
		(fp_line
			(start 0.7874 -0.4064)
			(end 0.7874 0.4064)
			(stroke
				(width 0.1524)
				(type default)
			)
			(layer "F.SilkS")
		)
		(fp_line
			(start 0.7874 0.4064)
			(end -0.7874 0.4064)
			(stroke
				(width 0.1524)
				(type default)
			)
			(layer "F.SilkS")
		)
		(fp_line
			(start -0.67945 -0.305054)
			(end -0.12065 -0.305054)
			(stroke
				(width 0.1)
				(type default)
			)
			(layer "F.Fab")
		)
		(fp_line
			(start -0.67945 0.3048)
			(end -0.67945 -0.305054)
			(stroke
				(width 0.1)
				(type default)
			)
			(layer "F.Fab")
		)
		(fp_line
			(start -0.12065 -0.305054)
			(end -0.12065 -0.2794)
			(stroke
				(width 0.1)
				(type default)
			)
			(layer "F.Fab")
		)
		(fp_line
			(start -0.12065 -0.2794)
			(end 0.12065 -0.2794)
			(stroke
				(width 0.1)
				(type default)
			)
			(layer "F.Fab")
		)
		(fp_line
			(start -0.12065 0.2794)
			(end -0.12065 0.3048)
			(stroke
				(width 0.1)
				(type default)
			)
			(layer "F.Fab")
		)
		(fp_line
			(start -0.12065 0.3048)
			(end -0.67945 0.3048)
			(stroke
				(width 0.1)
				(type default)
			)
			(layer "F.Fab")
		)
		(fp_line
			(start 0.120396 0.2794)
			(end -0.12065 0.2794)
			(stroke
				(width 0.1)
				(type default)
			)
			(layer "F.Fab")
		)
		(fp_line
			(start 0.120396 0.3048)
			(end 0.120396 0.2794)
			(stroke
				(width 0.1)
				(type default)
			)
			(layer "F.Fab")
		)
		(fp_line
			(start 0.12065 -0.3048)
			(end 0.67945 -0.3048)
			(stroke
				(width 0.1)
				(type default)
			)
			(layer "F.Fab")
		)
		(fp_line
			(start 0.12065 -0.2794)
			(end 0.12065 -0.3048)
			(stroke
				(width 0.1)
				(type default)
			)
			(layer "F.Fab")
		)
		(fp_line
			(start 0.67945 -0.3048)
			(end 0.67945 0.3048)
			(stroke
				(width 0.1)
				(type default)
			)
			(layer "F.Fab")
		)
		(fp_line
			(start 0.67945 0.3048)
			(end 0.120396 0.3048)
			(stroke
				(width 0.1)
				(type default)
			)
			(layer "F.Fab")
		)
		(pad "1" smd circle
			(at -0.40005 0)
			(size 0 0)
			(layers "F.Cu" "F.Mask" "F.Paste")
			(net "GPU_3V3IO_RSVD1_FFU")
		)
		(pad "2" smd circle
			(at 0.40005 0)
			(size 0 0)
			(layers "F.Cu" "F.Mask" "F.Paste")
			(net "GPU_3V3IO_RSVD1_FFU_ISO")
		)
	)
)
